# T6G (Grand Teton) — schematic netlist excerpt (pin names and nets, part order shuffled) for the footprints in the layout excerpt that follows; sources: Cadence DE-HDL packaged netlist, KiCad conversion of 04192023_DAF0TMB3IC0_F0TG_MB_C_brd_V02_OCP.brd

DB3  TDR_3P  EMPTY  pkg TH2  page 260
  GND  = T1_GND
  IO1  = TDR_SE_45_OHM_IN2
  IO2  = TDR_SE_45_OHM_IN2

R3520  Q_RES  4.7K 5% CHIP  pkg 0402LF  page 247 : A = P3V3_OCP_V3_2 ; B = SMB_OCP_V3_2_3V3AUX_BUF_SDA
C7503  Q_CAP  0.1UF 10V 10% X7S  pkg C0201  page 344 : A = P1V8_CPU1_RT_1D ; B = GND
H53  HOLE  EMPTY  pkg TH  page 230 : \1\ = GND

(kicad_pcb
	(version 20260206)
	(generator "pcbnew")
	(generator_version "10.0")
	(general
		(thickness 1.6)
		(legacy_teardrops no)
	)
	(paper "A4")
	(title_block
		(title "04192023_DAF0TMB3IC0_F0TG_MB_C_brd_V02_OCP.brd")
		(comment 1 "Grand Teton / footprints 264-267 of 8354")
	)
	(layers
		(0 "F.Cu" signal "TOP")
		(4 "In1.Cu" signal "GND")
		(6 "In2.Cu" signal "IN1")
		(8 "In3.Cu" signal "GND1")
		(10 "In4.Cu" signal "IN2")
		(12 "In5.Cu" signal "GND2")
		(14 "In6.Cu" signal "IN3")
		(16 "In7.Cu" signal "GND3")
		(18 "In8.Cu" signal "VCC")
		(20 "In9.Cu" signal "VCC1")
		(22 "In10.Cu" signal "GND4")
		(24 "In11.Cu" signal "IN4")
		(26 "In12.Cu" signal "GND5")
		(28 "In13.Cu" signal "IN5")
		(30 "In14.Cu" signal "GND6")
		(32 "In15.Cu" signal "IN6")
		(34 "In16.Cu" signal "GND7")
		(2 "B.Cu" signal "BOTTOM")
		(9 "F.Adhes" user "F.Adhesive")
		(11 "B.Adhes" user "B.Adhesive")
		(13 "F.Paste" user "Package Geometry/Pastemask Top")
		(15 "B.Paste" user "Package Geometry/Pastemask Bottom")
		(5 "F.SilkS" user "Ref Des/Silkscreen Top")
		(7 "B.SilkS" user "Ref Des/Silkscreen Bottom")
		(1 "F.Mask" user "Board Geometry/Soldermask Top")
		(3 "B.Mask" user "Board Geometry/Soldermask Bottom")
		(17 "Dwgs.User" user "User.Drawings")
		(19 "Cmts.User" user "User.Comments")
		(21 "Eco1.User" user "User.Eco1")
		(23 "Eco2.User" user "User.Eco2")
		(25 "Edge.Cuts" user "Board Geometry/Outline")
		(27 "Margin" user)
		(31 "F.CrtYd" user "Package Geometry/Place Bound Top")
		(29 "B.CrtYd" user "Package Geometry/Place Bound Bottom")
		(35 "F.Fab" user "Ref Des/Assembly Top")
		(33 "B.Fab" user "Ref Des/Assembly Bottom")
	)
	(footprint ""
		(layer "F.Cu")
		(at 165.3032 -419.7096 180)
		(property "Reference" "C7503"
			(at 0 0 180)
			(layer "F.SilkS")
			(hide yes)
			(effects
				(font
					(size 1.27 1.27)
				)
			)
		)
		(property "Value" ""
			(at 0 0 180)
			(layer "F.Fab")
			(effects
				(font
					(size 1.27 1.27)
				)
			)
		)
		(duplicate_pad_numbers_are_jumpers no)
		(fp_line
			(start 0.299974 0.150114)
			(end -0.299974 0.150114)
			(stroke
				(width 0.1)
				(type default)
			)
			(layer "F.Fab")
		)
		(fp_line
			(start 0.299974 -0.150114)
			(end 0.299974 0.150114)
			(stroke
				(width 0.1)
				(type default)
			)
			(layer "F.Fab")
		)
		(fp_line
			(start -0.299974 0.150114)
			(end -0.299974 -0.150114)
			(stroke
				(width 0.1)
				(type default)
			)
			(layer "F.Fab")
		)
		(fp_line
			(start -0.299974 -0.150114)
			(end 0.299974 -0.150114)
			(stroke
				(width 0.1)
				(type default)
			)
			(layer "F.Fab")
		)
		(pad "1" smd rect
			(at -0.2667 0 180)
			(size 0.3048 0.381)
			(layers "F.Cu" "F.Mask" "F.Paste")
			(net "P1V8_CPU1_RT_1D")
		)
		(pad "2" smd rect
			(at 0.2667 0 180)
			(size 0.3048 0.381)
			(layers "F.Cu" "F.Mask" "F.Paste")
			(net "GND")
		)
	)
	(footprint ""
		(layer "F.Cu")
		(at 422.88206 -163.314888)
		(property "Reference" "H53"
			(at 2.1844 3.91287 0)
			(unlocked yes)
			(layer "F.SilkS")
			(effects
				(font
					(size 0.7874 0.5842)
					(thickness 0.1524)
				)
				(justify left)
			)
		)
		(property "Value" ""
			(at 0 0 0)
			(layer "F.Fab")
			(effects
				(font
					(size 1.27 1.27)
				)
			)
		)
		(duplicate_pad_numbers_are_jumpers no)
		(pad "1" thru_hole circle
			(at 0 0)
			(size 6.1976 6.1976)
			(drill 3.7338)
			(layers "*.Cu" "*.Mask")
			(remove_unused_layers no)
			(net "GND")
			(clearance -0.9779)
			(padstack
				(mode front_inner_back)
				(layer "Inner"
					(shape circle)
					(size 5.5372 5.5372)
					(clearance -0.6477)
				)
				(layer "B.Cu"
					(shape circle)
					(size 6.1976 6.1976)
					(clearance -0.9779)
				)
			)
		)
	)
	(footprint ""
		(layer "F.Cu")
		(at 479.35896 -202.351132 180)
		(property "Reference" "DB3"
			(at -1.527048 3.26771 0)
			(unlocked yes)
			(layer "F.SilkS")
			(effects
				(font
					(size 0.7874 0.5842)
					(thickness 0.1524)
				)
				(justify left)
			)
		)
		(property "Value" ""
			(at 0 0 180)
			(layer "F.Fab")
			(effects
				(font
					(size 1.27 1.27)
				)
			)
		)
		(duplicate_pad_numbers_are_jumpers no)
		(fp_line
			(start 3.330702 -4.771136)
			(end 0 4.011168)
			(stroke
				(width 0.1524)
				(type default)
			)
			(layer "F.SilkS")
		)
		(fp_line
			(start 0 4.011168)
			(end -3.330702 -4.771136)
			(stroke
				(width 0.1524)
				(type default)
			)
			(layer "F.SilkS")
		)
		(fp_line
			(start -3.330702 -4.771136)
			(end 3.330702 -4.771136)
			(stroke
				(width 0.1524)
				(type default)
			)
			(layer "F.SilkS")
		)
		(fp_line
			(start 3.330702 -4.771136)
			(end 0 4.011168)
			(stroke
				(width 0.1)
				(type default)
			)
			(layer "F.Fab")
		)
		(fp_line
			(start 0 4.011168)
			(end -3.330702 -4.771136)
			(stroke
				(width 0.1)
				(type default)
			)
			(layer "F.Fab")
		)
		(fp_line
			(start -3.330702 -4.771136)
			(end 3.330702 -4.771136)
			(stroke
				(width 0.1)
				(type default)
			)
			(layer "F.Fab")
		)
		(pad "1" thru_hole circle
			(at 0 0 180)
			(size 2.159 2.159)
			(drill 1.7018)
			(layers "*.Cu" "*.Mask")
			(remove_unused_layers no)
			(net "T1_GND")
			(clearance 0.0254)
			(thermal_gap 0.0254)
		)
		(pad "2" thru_hole circle
			(at -1.27 -3.348736 180)
			(size 2.159 2.159)
			(drill 1.7018)
			(layers "*.Cu" "*.Mask")
			(remove_unused_layers no)
			(net "TDR_SE_45_OHM_IN2")
			(clearance 0.0254)
			(thermal_gap 0.0254)
		)
		(pad "3" thru_hole circle
			(at 1.27 -3.348736 180)
			(size 2.159 2.159)
			(drill 1.7018)
			(layers "*.Cu" "*.Mask")
			(remove_unused_layers no)
			(net "TDR_SE_45_OHM_IN2")
			(clearance 0.0254)
			(thermal_gap 0.0254)
		)
	)
	(footprint ""
		(layer "F.Cu")
		(at 152.849326 -38.00856 180)
		(property "Reference" "R3520"
			(at 0 0 180)
			(layer "F.SilkS")
			(hide yes)
			(effects
				(font
					(size 1.27 1.27)
				)
			)
		)
		(property "Value" ""
			(at 0 0 180)
			(layer "F.Fab")
			(effects
				(font
					(size 1.27 1.27)
				)
			)
		)
		(duplicate_pad_numbers_are_jumpers no)
		(fp_line
			(start 0.7874 0.4064)
			(end -0.7874 0.4064)
			(stroke
				(width 0.1524)
				(type default)
			)
			(layer "F.SilkS")
		)
		(fp_line
			(start 0.7874 -0.4064)
			(end 0.7874 0.4064)
			(stroke
				(width 0.1524)
				(type default)
			)
			(layer "F.SilkS")
		)
		(fp_line
			(start -0.7874 0.4064)
			(end -0.7874 -0.4064)
			(stroke
				(width 0.1524)
				(type default)
			)
			(layer "F.SilkS")
		)
		(fp_line
			(start -0.7874 -0.4064)
			(end 0.7874 -0.4064)
			(stroke
				(width 0.1524)
				(type default)
			)
			(layer "F.SilkS")
		)
		(fp_line
			(start 0.67945 0.3048)
			(end 0.120396 0.3048)
			(stroke
				(width 0.1)
				(type default)
			)
			(layer "F.Fab")
		)
		(fp_line
			(start 0.67945 -0.3048)
			(end 0.67945 0.3048)
			(stroke
				(width 0.1)
				(type default)
			)
			(layer "F.Fab")
		)
		(fp_line
			(start 0.12065 -0.2794)
			(end 0.12065 -0.3048)
			(stroke
				(width 0.1)
				(type default)
			)
			(layer "F.Fab")
		)
		(fp_line
			(start 0.12065 -0.3048)
			(end 0.67945 -0.3048)
			(stroke
				(width 0.1)
				(type default)
			)
			(layer "F.Fab")
		)
		(fp_line
			(start 0.120396 0.3048)
			(end 0.120396 0.2794)
			(stroke
				(width 0.1)
				(type default)
			)
			(layer "F.Fab")
		)
		(fp_line
			(start 0.120396 0.2794)
			(end -0.12065 0.2794)
			(stroke
				(width 0.1)
				(type default)
			)
			(layer "F.Fab")
		)
		(fp_line
			(start -0.12065 0.3048)
			(end -0.67945 0.3048)
			(stroke
				(width 0.1)
				(type default)
			)
			(layer "F.Fab")
		)
		(fp_line
			(start -0.12065 0.2794)
			(end -0.12065 0.3048)
			(stroke
				(width 0.1)
				(type default)
			)
			(layer "F.Fab")
		)
		(fp_line
			(start -0.12065 -0.2794)
			(end 0.12065 -0.2794)
			(stroke
				(width 0.1)
				(type default)
			)
			(layer "F.Fab")
		)
		(fp_line
			(start -0.12065 -0.305054)
			(end -0.12065 -0.2794)
			(stroke
				(width 0.1)
				(type default)
			)
			(layer "F.Fab")
		)
		(fp_line
			(start -0.67945 0.3048)
			(end -0.67945 -0.305054)
			(stroke
				(width 0.1)
				(type default)
			)
			(layer "F.Fab")
		)
		(fp_line
			(start -0.67945 -0.305054)
			(end -0.12065 -0.305054)
			(stroke
				(width 0.1)
				(type default)
			)
			(layer "F.Fab")
		)
		(pad "1" smd circle
			(at -0.40005 0 180)
			(size 0 0)
			(layers "F.Cu" "F.Mask" "F.Paste")
			(net "P3V3_OCP_V3_2")
		)
		(pad "2" smd circle
			(at 0.40005 0 180)
			(size 0 0)
			(layers "F.Cu" "F.Mask" "F.Paste")
			(net "SMB_OCP_V3_2_3V3AUX_BUF_SDA")
		)
	)
)
